(kicad_pcb
	(version 20260206)
	(generator "pcbnew")
	(generator_version "10.0")
	(general
		(thickness 1.6)
		(legacy_teardrops no)
	)
	(paper "A4")
	(title_block
		(title "04192023_DAF0TMB3IC0_F0TG_MB_C_brd_V02_OCP.brd")
		(comment 1 "Grand Teton / footprints 2286-2293 of 8354")
	)
	(layers
		(0 "F.Cu" signal "TOP")
		(4 "In1.Cu" signal "GND")
		(6 "In2.Cu" signal "IN1")
		(8 "In3.Cu" signal "GND1")
		(10 "In4.Cu" signal "IN2")
		(12 "In5.Cu" signal "GND2")
		(14 "In6.Cu" signal "IN3")
		(16 "In7.Cu" signal "GND3")
		(18 "In8.Cu" signal "VCC")
		(20 "In9.Cu" signal "VCC1")
		(22 "In10.Cu" signal "GND4")
		(24 "In11.Cu" signal "IN4")
		(26 "In12.Cu" signal "GND5")
		(28 "In13.Cu" signal "IN5")
		(30 "In14.Cu" signal "GND6")
		(32 "In15.Cu" signal "IN6")
		(34 "In16.Cu" signal "GND7")
		(2 "B.Cu" signal "BOTTOM")
		(9 "F.Adhes" user "F.Adhesive")
		(11 "B.Adhes" user "B.Adhesive")
		(13 "F.Paste" user "Package Geometry/Pastemask Top")
		(15 "B.Paste" user "Package Geometry/Pastemask Bottom")
		(5 "F.SilkS" user "Ref Des/Silkscreen Top")
		(7 "B.SilkS" user "Ref Des/Silkscreen Bottom")
		(1 "F.Mask" user "Board Geometry/Soldermask Top")
		(3 "B.Mask" user "Board Geometry/Soldermask Bottom")
		(17 "Dwgs.User" user "User.Drawings")
		(19 "Cmts.User" user "User.Comments")
		(21 "Eco1.User" user "User.Eco1")
		(23 "Eco2.User" user "User.Eco2")
		(25 "Edge.Cuts" user "Board Geometry/Outline")
		(27 "Margin" user)
		(31 "F.CrtYd" user "Package Geometry/Place Bound Top")
		(29 "B.CrtYd" user "Package Geometry/Place Bound Bottom")
		(35 "F.Fab" user "Ref Des/Assembly Top")
		(33 "B.Fab" user "Ref Des/Assembly Bottom")
	)
	(footprint ""
		(layer "F.Cu")
		(at 83.621626 -58.452004 90)
		(property "Reference" "R3633"
			(at -4.884674 -1.833626 0)
			(unlocked yes)
			(layer "F.SilkS")
			(effects
				(font
					(size 0.7874 0.5842)
					(thickness 0.1524)
				)
				(justify left)
			)
		)
		(property "Value" ""
			(at 0 0 90)
			(layer "F.Fab")
			(effects
				(font
					(size 1.27 1.27)
				)
			)
		)
		(duplicate_pad_numbers_are_jumpers no)
		(fp_line
			(start 3.937508 -1.8796)
			(end -3.937508 -1.8796)
			(stroke
				(width 0.1524)
				(type default)
			)
			(layer "F.SilkS")
		)
		(fp_line
			(start -3.937508 -1.8796)
			(end -3.937508 1.8796)
			(stroke
				(width 0.1524)
				(type default)
			)
			(layer "F.SilkS")
		)
		(fp_line
			(start 3.937508 1.8796)
			(end 3.937508 -1.8796)
			(stroke
				(width 0.1524)
				(type default)
			)
			(layer "F.SilkS")
		)
		(fp_line
			(start -3.937508 1.8796)
			(end 3.937508 1.8796)
			(stroke
				(width 0.1524)
				(type default)
			)
			(layer "F.SilkS")
		)
		(fp_line
			(start 3.275076 -1.674876)
			(end -3.275076 -1.674876)
			(stroke
				(width 0.1)
				(type default)
			)
			(layer "F.Fab")
		)
		(fp_line
			(start -3.275076 -1.674876)
			(end -3.275076 1.674876)
			(stroke
				(width 0.1)
				(type default)
			)
			(layer "F.Fab")
		)
		(fp_line
			(start 3.275076 1.674876)
			(end 3.275076 -1.674876)
			(stroke
				(width 0.1)
				(type default)
			)
			(layer "F.Fab")
		)
		(fp_line
			(start -3.275076 1.674876)
			(end 3.275076 1.674876)
			(stroke
				(width 0.1)
				(type default)
			)
			(layer "F.Fab")
		)
		(pad "1" smd rect
			(at -2.350008 0 90)
			(size 2.921 3.5052)
			(layers "F.Cu" "F.Mask" "F.Paste")
			(net "P3V3_OCP_V3_2")
		)
		(pad "2" smd rect
			(at 2.350008 0 90)
			(size 2.921 3.5052)
			(layers "F.Cu" "F.Mask" "F.Paste")
			(net "P3V3_OCP_V3_2_R")
		)
	)
	(footprint ""
		(layer "F.Cu")
		(at 287.87217 -351.100644)
		(property "Reference" "PC149_2"
			(at 0 0 0)
			(layer "F.SilkS")
			(hide yes)
			(effects
				(font
					(size 1.27 1.27)
				)
			)
		)
		(property "Value" ""
			(at 0 0 0)
			(layer "F.Fab")
			(effects
				(font
					(size 1.27 1.27)
				)
			)
		)
		(duplicate_pad_numbers_are_jumpers no)
		(fp_line
			(start -0.7874 -0.4064)
			(end 0.7874 -0.4064)
			(stroke
				(width 0.1524)
				(type default)
			)
			(layer "F.SilkS")
		)
		(fp_line
			(start -0.7874 0.4064)
			(end -0.7874 -0.4064)
			(stroke
				(width 0.1524)
				(type default)
			)
			(layer "F.SilkS")
		)
		(fp_line
			(start 0.7874 -0.4064)
			(end 0.7874 0.4064)
			(stroke
				(width 0.1524)
				(type default)
			)
			(layer "F.SilkS")
		)
		(fp_line
			(start 0.7874 0.4064)
			(end -0.7874 0.4064)
			(stroke
				(width 0.1524)
				(type default)
			)
			(layer "F.SilkS")
		)
		(fp_line
			(start -0.67945 -0.305054)
			(end -0.12065 -0.305054)
			(stroke
				(width 0.1)
				(type default)
			)
			(layer "F.Fab")
		)
		(fp_line
			(start -0.67945 0.3048)
			(end -0.67945 -0.305054)
			(stroke
				(width 0.1)
				(type default)
			)
			(layer "F.Fab")
		)
		(fp_line
			(start -0.12065 -0.305054)
			(end -0.12065 -0.2794)
			(stroke
				(width 0.1)
				(type default)
			)
			(layer "F.Fab")
		)
		(fp_line
			(start -0.12065 -0.2794)
			(end 0.12065 -0.2794)
			(stroke
				(width 0.1)
				(type default)
			)
			(layer "F.Fab")
		)
		(fp_line
			(start -0.12065 0.2794)
			(end -0.12065 0.3048)
			(stroke
				(width 0.1)
				(type default)
			)
			(layer "F.Fab")
		)
		(fp_line
			(start -0.12065 0.3048)
			(end -0.67945 0.3048)
			(stroke
				(width 0.1)
				(type default)
			)
			(layer "F.Fab")
		)
		(fp_line
			(start 0.120396 0.2794)
			(end -0.12065 0.2794)
			(stroke
				(width 0.1)
				(type default)
			)
			(layer "F.Fab")
		)
		(fp_line
			(start 0.120396 0.3048)
			(end 0.120396 0.2794)
			(stroke
				(width 0.1)
				(type default)
			)
			(layer "F.Fab")
		)
		(fp_line
			(start 0.12065 -0.3048)
			(end 0.67945 -0.3048)
			(stroke
				(width 0.1)
				(type default)
			)
			(layer "F.Fab")
		)
		(fp_line
			(start 0.12065 -0.2794)
			(end 0.12065 -0.3048)
			(stroke
				(width 0.1)
				(type default)
			)
			(layer "F.Fab")
		)
		(fp_line
			(start 0.67945 -0.3048)
			(end 0.67945 0.3048)
			(stroke
				(width 0.1)
				(type default)
			)
			(layer "F.Fab")
		)
		(fp_line
			(start 0.67945 0.3048)
			(end 0.120396 0.3048)
			(stroke
				(width 0.1)
				(type default)
			)
			(layer "F.Fab")
		)
		(pad "1" smd circle
			(at -0.40005 0)
			(size 0 0)
			(layers "F.Cu" "F.Mask" "F.Paste")
			(net "SW_P12V_AUX_PVDDIO_P0_FLT")
		)
		(pad "2" smd circle
			(at 0.40005 0)
			(size 0 0)
			(layers "F.Cu" "F.Mask" "F.Paste")
			(net "GND")
		)
	)
	(footprint ""
		(layer "F.Cu")
		(at 386.211826 -57.2135 180)
		(property "Reference" "R1627"
			(at 0 0 180)
			(layer "F.SilkS")
			(hide yes)
			(effects
				(font
					(size 1.27 1.27)
				)
			)
		)
		(property "Value" ""
			(at 0 0 180)
			(layer "F.Fab")
			(effects
				(font
					(size 1.27 1.27)
				)
			)
		)
		(duplicate_pad_numbers_are_jumpers no)
		(fp_line
			(start 0.7874 0.4064)
			(end -0.7874 0.4064)
			(stroke
				(width 0.1524)
				(type default)
			)
			(layer "F.SilkS")
		)
		(fp_line
			(start 0.7874 -0.4064)
			(end 0.7874 0.4064)
			(stroke
				(width 0.1524)
				(type default)
			)
			(layer "F.SilkS")
		)
		(fp_line
			(start -0.7874 0.4064)
			(end -0.7874 -0.4064)
			(stroke
				(width 0.1524)
				(type default)
			)
			(layer "F.SilkS")
		)
		(fp_line
			(start -0.7874 -0.4064)
			(end 0.7874 -0.4064)
			(stroke
				(width 0.1524)
				(type default)
			)
			(layer "F.SilkS")
		)
		(fp_line
			(start 0.67945 0.3048)
			(end 0.120396 0.3048)
			(stroke
				(width 0.1)
				(type default)
			)
			(layer "F.Fab")
		)
		(fp_line
			(start 0.67945 -0.3048)
			(end 0.67945 0.3048)
			(stroke
				(width 0.1)
				(type default)
			)
			(layer "F.Fab")
		)
		(fp_line
			(start 0.12065 -0.2794)
			(end 0.12065 -0.3048)
			(stroke
				(width 0.1)
				(type default)
			)
			(layer "F.Fab")
		)
		(fp_line
			(start 0.12065 -0.3048)
			(end 0.67945 -0.3048)
			(stroke
				(width 0.1)
				(type default)
			)
			(layer "F.Fab")
		)
		(fp_line
			(start 0.120396 0.3048)
			(end 0.120396 0.2794)
			(stroke
				(width 0.1)
				(type default)
			)
			(layer "F.Fab")
		)
		(fp_line
			(start 0.120396 0.2794)
			(end -0.12065 0.2794)
			(stroke
				(width 0.1)
				(type default)
			)
			(layer "F.Fab")
		)
		(fp_line
			(start -0.12065 0.3048)
			(end -0.67945 0.3048)
			(stroke
				(width 0.1)
				(type default)
			)
			(layer "F.Fab")
		)
		(fp_line
			(start -0.12065 0.2794)
			(end -0.12065 0.3048)
			(stroke
				(width 0.1)
				(type default)
			)
			(layer "F.Fab")
		)
		(fp_line
			(start -0.12065 -0.2794)
			(end 0.12065 -0.2794)
			(stroke
				(width 0.1)
				(type default)
			)
			(layer "F.Fab")
		)
		(fp_line
			(start -0.12065 -0.305054)
			(end -0.12065 -0.2794)
			(stroke
				(width 0.1)
				(type default)
			)
			(layer "F.Fab")
		)
		(fp_line
			(start -0.67945 0.3048)
			(end -0.67945 -0.305054)
			(stroke
				(width 0.1)
				(type default)
			)
			(layer "F.Fab")
		)
		(fp_line
			(start -0.67945 -0.305054)
			(end -0.12065 -0.305054)
			(stroke
				(width 0.1)
				(type default)
			)
			(layer "F.Fab")
		)
		(pad "1" smd circle
			(at -0.40005 0 180)
			(size 0 0)
			(layers "F.Cu" "F.Mask" "F.Paste")
			(net "PVDD18_S5_P0")
		)
		(pad "2" smd circle
			(at 0.40005 0 180)
			(size 0 0)
			(layers "F.Cu" "F.Mask" "F.Paste")
			(net "HDT_HDR_TDI")
		)
	)
	(footprint ""
		(layer "F.Cu")
		(at 104.267 -415.798)
		(property "Reference" "R578"
			(at 0 0 0)
			(layer "F.SilkS")
			(hide yes)
			(effects
				(font
					(size 1.27 1.27)
				)
			)
		)
		(property "Value" ""
			(at 0 0 0)
			(layer "F.Fab")
			(effects
				(font
					(size 1.27 1.27)
				)
			)
		)
		(duplicate_pad_numbers_are_jumpers no)
		(fp_line
			(start -0.7874 -0.4064)
			(end 0.7874 -0.4064)
			(stroke
				(width 0.1524)
				(type default)
			)
			(layer "F.SilkS")
		)
		(fp_line
			(start -0.7874 0.4064)
			(end -0.7874 -0.4064)
			(stroke
				(width 0.1524)
				(type default)
			)
			(layer "F.SilkS")
		)
		(fp_line
			(start 0.7874 -0.4064)
			(end 0.7874 0.4064)
			(stroke
				(width 0.1524)
				(type default)
			)
			(layer "F.SilkS")
		)
		(fp_line
			(start 0.7874 0.4064)
			(end -0.7874 0.4064)
			(stroke
				(width 0.1524)
				(type default)
			)
			(layer "F.SilkS")
		)
		(fp_line
			(start -0.67945 -0.305054)
			(end -0.12065 -0.305054)
			(stroke
				(width 0.1)
				(type default)
			)
			(layer "F.Fab")
		)
		(fp_line
			(start -0.67945 0.3048)
			(end -0.67945 -0.305054)
			(stroke
				(width 0.1)
				(type default)
			)
			(layer "F.Fab")
		)
		(fp_line
			(start -0.12065 -0.305054)
			(end -0.12065 -0.2794)
			(stroke
				(width 0.1)
				(type default)
			)
			(layer "F.Fab")
		)
		(fp_line
			(start -0.12065 -0.2794)
			(end 0.12065 -0.2794)
			(stroke
				(width 0.1)
				(type default)
			)
			(layer "F.Fab")
		)
		(fp_line
			(start -0.12065 0.2794)
			(end -0.12065 0.3048)
			(stroke
				(width 0.1)
				(type default)
			)
			(layer "F.Fab")
		)
		(fp_line
			(start -0.12065 0.3048)
			(end -0.67945 0.3048)
			(stroke
				(width 0.1)
				(type default)
			)
			(layer "F.Fab")
		)
		(fp_line
			(start 0.120396 0.2794)
			(end -0.12065 0.2794)
			(stroke
				(width 0.1)
				(type default)
			)
			(layer "F.Fab")
		)
		(fp_line
			(start 0.120396 0.3048)
			(end 0.120396 0.2794)
			(stroke
				(width 0.1)
				(type default)
			)
			(layer "F.Fab")
		)
		(fp_line
			(start 0.12065 -0.3048)
			(end 0.67945 -0.3048)
			(stroke
				(width 0.1)
				(type default)
			)
			(layer "F.Fab")
		)
		(fp_line
			(start 0.12065 -0.2794)
			(end 0.12065 -0.3048)
			(stroke
				(width 0.1)
				(type default)
			)
			(layer "F.Fab")
		)
		(fp_line
			(start 0.67945 -0.3048)
			(end 0.67945 0.3048)
			(stroke
				(width 0.1)
				(type default)
			)
			(layer "F.Fab")
		)
		(fp_line
			(start 0.67945 0.3048)
			(end 0.120396 0.3048)
			(stroke
				(width 0.1)
				(type default)
			)
			(layer "F.Fab")
		)
		(pad "1" smd circle
			(at -0.40005 0)
			(size 0 0)
			(layers "F.Cu" "F.Mask" "F.Paste")
			(net "P3V3_AUX")
		)
		(pad "2" smd circle
			(at 0.40005 0)
			(size 0 0)
			(layers "F.Cu" "F.Mask" "F.Paste")
			(net "CLK_9ZXL045_P1_SADR0")
		)
	)
	(footprint ""
		(layer "F.Cu")
		(at 362.025438 -411.354016)
		(property "Reference" "R9002"
			(at 0 0 0)
			(layer "F.SilkS")
			(hide yes)
			(effects
				(font
					(size 1.27 1.27)
				)
			)
		)
		(property "Value" ""
			(at 0 0 0)
			(layer "F.Fab")
			(effects
				(font
					(size 1.27 1.27)
				)
			)
		)
		(duplicate_pad_numbers_are_jumpers no)
		(fp_line
			(start -0.7874 -0.4064)
			(end 0.7874 -0.4064)
			(stroke
				(width 0.1524)
				(type default)
			)
			(layer "F.SilkS")
		)
		(fp_line
			(start -0.7874 0.4064)
			(end -0.7874 -0.4064)
			(stroke
				(width 0.1524)
				(type default)
			)
			(layer "F.SilkS")
		)
		(fp_line
			(start 0.7874 -0.4064)
			(end 0.7874 0.4064)
			(stroke
				(width 0.1524)
				(type default)
			)
			(layer "F.SilkS")
		)
		(fp_line
			(start 0.7874 0.4064)
			(end -0.7874 0.4064)
			(stroke
				(width 0.1524)
				(type default)
			)
			(layer "F.SilkS")
		)
		(fp_line
			(start -0.67945 -0.305054)
			(end -0.12065 -0.305054)
			(stroke
				(width 0.1)
				(type default)
			)
			(layer "F.Fab")
		)
		(fp_line
			(start -0.67945 0.3048)
			(end -0.67945 -0.305054)
			(stroke
				(width 0.1)
				(type default)
			)
			(layer "F.Fab")
		)
		(fp_line
			(start -0.12065 -0.305054)
			(end -0.12065 -0.2794)
			(stroke
				(width 0.1)
				(type default)
			)
			(layer "F.Fab")
		)
		(fp_line
			(start -0.12065 -0.2794)
			(end 0.12065 -0.2794)
			(stroke
				(width 0.1)
				(type default)
			)
			(layer "F.Fab")
		)
		(fp_line
			(start -0.12065 0.2794)
			(end -0.12065 0.3048)
			(stroke
				(width 0.1)
				(type default)
			)
			(layer "F.Fab")
		)
		(fp_line
			(start -0.12065 0.3048)
			(end -0.67945 0.3048)
			(stroke
				(width 0.1)
				(type default)
			)
			(layer "F.Fab")
		)
		(fp_line
			(start 0.120396 0.2794)
			(end -0.12065 0.2794)
			(stroke
				(width 0.1)
				(type default)
			)
			(layer "F.Fab")
		)
		(fp_line
			(start 0.120396 0.3048)
			(end 0.120396 0.2794)
			(stroke
				(width 0.1)
				(type default)
			)
			(layer "F.Fab")
		)
		(fp_line
			(start 0.12065 -0.3048)
			(end 0.67945 -0.3048)
			(stroke
				(width 0.1)
				(type default)
			)
			(layer "F.Fab")
		)
		(fp_line
			(start 0.12065 -0.2794)
			(end 0.12065 -0.3048)
			(stroke
				(width 0.1)
				(type default)
			)
			(layer "F.Fab")
		)
		(fp_line
			(start 0.67945 -0.3048)
			(end 0.67945 0.3048)
			(stroke
				(width 0.1)
				(type default)
			)
			(layer "F.Fab")
		)
		(fp_line
			(start 0.67945 0.3048)
			(end 0.120396 0.3048)
			(stroke
				(width 0.1)
				(type default)
			)
			(layer "F.Fab")
		)
		(pad "1" smd circle
			(at -0.40005 0)
			(size 0 0)
			(layers "F.Cu" "F.Mask" "F.Paste")
			(net "P3V3_AUX")
		)
		(pad "2" smd circle
			(at 0.40005 0)
			(size 0 0)
			(layers "F.Cu" "F.Mask" "F.Paste")
			(net "PRSNT_CABLE_SWB_B1_N")
		)
	)
	(footprint ""
		(layer "F.Cu")
		(at 359.568242 -406.567386 -90)
		(property "Reference" "R9016"
			(at 0 0 270)
			(layer "F.SilkS")
			(hide yes)
			(effects
				(font
					(size 1.27 1.27)
				)
			)
		)
		(property "Value" ""
			(at 0 0 270)
			(layer "F.Fab")
			(effects
				(font
					(size 1.27 1.27)
				)
			)
		)
		(duplicate_pad_numbers_are_jumpers no)
		(fp_line
			(start -0.7874 0.4064)
			(end -0.7874 -0.4064)
			(stroke
				(width 0.1524)
				(type default)
			)
			(layer "F.SilkS")
		)
		(fp_line
			(start 0.7874 0.4064)
			(end -0.7874 0.4064)
			(stroke
				(width 0.1524)
				(type default)
			)
			(layer "F.SilkS")
		)
		(fp_line
			(start -0.7874 -0.4064)
			(end 0.7874 -0.4064)
			(stroke
				(width 0.1524)
				(type default)
			)
			(layer "F.SilkS")
		)
		(fp_line
			(start 0.7874 -0.4064)
			(end 0.7874 0.4064)
			(stroke
				(width 0.1524)
				(type default)
			)
			(layer "F.SilkS")
		)
		(fp_line
			(start -0.67945 0.3048)
			(end -0.67945 -0.305054)
			(stroke
				(width 0.1)
				(type default)
			)
			(layer "F.Fab")
		)
		(fp_line
			(start -0.12065 0.3048)
			(end -0.67945 0.3048)
			(stroke
				(width 0.1)
				(type default)
			)
			(layer "F.Fab")
		)
		(fp_line
			(start 0.120396 0.3048)
			(end 0.120396 0.2794)
			(stroke
				(width 0.1)
				(type default)
			)
			(layer "F.Fab")
		)
		(fp_line
			(start 0.67945 0.3048)
			(end 0.120396 0.3048)
			(stroke
				(width 0.1)
				(type default)
			)
			(layer "F.Fab")
		)
		(fp_line
			(start -0.12065 0.2794)
			(end -0.12065 0.3048)
			(stroke
				(width 0.1)
				(type default)
			)
			(layer "F.Fab")
		)
		(fp_line
			(start 0.120396 0.2794)
			(end -0.12065 0.2794)
			(stroke
				(width 0.1)
				(type default)
			)
			(layer "F.Fab")
		)
		(fp_line
			(start -0.12065 -0.2794)
			(end 0.12065 -0.2794)
			(stroke
				(width 0.1)
				(type default)
			)
			(layer "F.Fab")
		)
		(fp_line
			(start 0.12065 -0.2794)
			(end 0.12065 -0.3048)
			(stroke
				(width 0.1)
				(type default)
			)
			(layer "F.Fab")
		)
		(fp_line
			(start 0.12065 -0.3048)
			(end 0.67945 -0.3048)
			(stroke
				(width 0.1)
				(type default)
			)
			(layer "F.Fab")
		)
		(fp_line
			(start 0.67945 -0.3048)
			(end 0.67945 0.3048)
			(stroke
				(width 0.1)
				(type default)
			)
			(layer "F.Fab")
		)
		(fp_line
			(start -0.67945 -0.305054)
			(end -0.12065 -0.305054)
			(stroke
				(width 0.1)
				(type default)
			)
			(layer "F.Fab")
		)
		(fp_line
			(start -0.12065 -0.305054)
			(end -0.12065 -0.2794)
			(stroke
				(width 0.1)
				(type default)
			)
			(layer "F.Fab")
		)
		(pad "1" smd circle
			(at -0.40005 0 270)
			(size 0 0)
			(layers "F.Cu" "F.Mask" "F.Paste")
			(net "P3V3_AUX")
		)
		(pad "2" smd circle
			(at 0.40005 0 270)
			(size 0 0)
			(layers "F.Cu" "F.Mask" "F.Paste")
			(net "PRSNT_CABLE_GPU_A3")
		)
	)
	(footprint ""
		(layer "F.Cu")
		(at 54.716172 -167.14597)
		(property "Reference" "H8028"
			(at -5.808218 -4.25069 0)
			(unlocked yes)
			(layer "F.SilkS")
			(effects
				(font
					(size 0.7874 0.5842)
					(thickness 0.1524)
				)
				(justify left)
			)
		)
		(property "Value" ""
			(at 0 0 0)
			(layer "F.Fab")
			(effects
				(font
					(size 1.27 1.27)
				)
			)
		)
		(duplicate_pad_numbers_are_jumpers no)
		(pad "1" thru_hole circle
			(at 0 0)
			(size 6.1976 6.1976)
			(drill 3.7338)
			(layers "*.Cu" "*.Mask")
			(remove_unused_layers no)
			(net "GND")
			(clearance -0.9779)
			(padstack
				(mode front_inner_back)
				(layer "Inner"
					(shape circle)
					(size 5.5372 5.5372)
					(clearance -0.6477)
				)
				(layer "B.Cu"
					(shape circle)
					(size 6.1976 6.1976)
					(clearance -0.9779)
				)
			)
		)
	)
	(footprint ""
		(layer "F.Cu")
		(at 389.653018 -402.7424 -90)
		(property "Reference" "R1124"
			(at 0 0 270)
			(layer "F.SilkS")
			(hide yes)
			(effects
				(font
					(size 1.27 1.27)
				)
			)
		)
		(property "Value" ""
			(at 0 0 270)
			(layer "F.Fab")
			(effects
				(font
					(size 1.27 1.27)
				)
			)
		)
		(duplicate_pad_numbers_are_jumpers no)
		(fp_line
			(start -0.32512 0.175006)
			(end -0.32512 -0.175006)
			(stroke
				(width 0.1)
				(type default)
			)
			(layer "F.Fab")
		)
		(fp_line
			(start 0.32512 0.175006)
			(end -0.32512 0.175006)
			(stroke
				(width 0.1)
				(type default)
			)
			(layer "F.Fab")
		)
		(fp_line
			(start -0.32512 -0.175006)
			(end 0.32512 -0.175006)
			(stroke
				(width 0.1)
				(type default)
			)
			(layer "F.Fab")
		)
		(fp_line
			(start 0.32512 -0.175006)
			(end 0.32512 0.175006)
			(stroke
				(width 0.1)
				(type default)
			)
			(layer "F.Fab")
		)
		(pad "1" smd rect
			(at -0.2667 0 270)
			(size 0.3048 0.381)
			(layers "F.Cu" "F.Mask" "F.Paste")
			(net "RT_CPU0_P3_VQPS")
		)
		(pad "2" smd rect
			(at 0.2667 0 90)
			(size 0.3048 0.381)
			(layers "F.Cu" "F.Mask" "F.Paste")
			(net "GND")
		)
	)
)
